(kicad_pcb
	(version 20260206)
	(generator "pcbnew")
	(generator_version "10.0")
	(general
		(thickness 1.6)
		(legacy_teardrops no)
	)
	(paper "A4")
	(title_block
		(title "01162023_DA0F0TEBIF0_F0T_Expander_BD_F_brd_V02_OCP.brd")
		(comment 1 "Grand Teton / footprints 3068-3074 of 9728")
	)
	(layers
		(0 "F.Cu" signal "TOP")
		(4 "In1.Cu" signal "GND")
		(6 "In2.Cu" signal "VCC")
		(8 "In3.Cu" signal "VCC1")
		(10 "In4.Cu" signal "GND1")
		(12 "In5.Cu" signal "IN1")
		(14 "In6.Cu" signal "GND2")
		(16 "In7.Cu" signal "IN2")
		(18 "In8.Cu" signal "GND3")
		(20 "In9.Cu" signal "IN3")
		(22 "In10.Cu" signal "GND4")
		(24 "In11.Cu" signal "IN4")
		(26 "In12.Cu" signal "GND5")
		(28 "In13.Cu" signal "IN5")
		(30 "In14.Cu" signal "GND6")
		(32 "In15.Cu" signal "IN6")
		(34 "In16.Cu" signal "GND7")
		(2 "B.Cu" signal "BOTTOM")
		(9 "F.Adhes" user "F.Adhesive")
		(11 "B.Adhes" user "B.Adhesive")
		(13 "F.Paste" user "Package Geometry/Pastemask Top")
		(15 "B.Paste" user "Package Geometry/Pastemask Bottom")
		(5 "F.SilkS" user "Ref Des/Silkscreen Top")
		(7 "B.SilkS" user "Ref Des/Silkscreen Bottom")
		(1 "F.Mask" user "Board Geometry/Soldermask Top")
		(3 "B.Mask" user "Board Geometry/Soldermask Bottom")
		(17 "Dwgs.User" user "User.Drawings")
		(19 "Cmts.User" user "User.Comments")
		(21 "Eco1.User" user "User.Eco1")
		(23 "Eco2.User" user "User.Eco2")
		(25 "Edge.Cuts" user "Board Geometry/Outline")
		(27 "Margin" user)
		(31 "F.CrtYd" user "Package Geometry/Place Bound Top")
		(29 "B.CrtYd" user "Package Geometry/Place Bound Bottom")
		(35 "F.Fab" user "Ref Des/Assembly Top")
		(33 "B.Fab" user "Ref Des/Assembly Bottom")
	)
	(footprint ""
		(layer "F.Cu")
		(at 413.588708 -193.730118 180)
		(property "Reference" "R6437"
			(at 0 0 180)
			(layer "F.SilkS")
			(hide yes)
			(effects
				(font
					(size 1.27 1.27)
				)
			)
		)
		(property "Value" ""
			(at 0 0 180)
			(layer "F.Fab")
			(effects
				(font
					(size 1.27 1.27)
				)
			)
		)
		(duplicate_pad_numbers_are_jumpers no)
		(fp_line
			(start 0.7874 0.4064)
			(end -0.7874 0.4064)
			(stroke
				(width 0.1524)
				(type default)
			)
			(layer "F.SilkS")
		)
		(fp_line
			(start 0.7874 -0.4064)
			(end 0.7874 0.4064)
			(stroke
				(width 0.1524)
				(type default)
			)
			(layer "F.SilkS")
		)
		(fp_line
			(start -0.7874 0.4064)
			(end -0.7874 -0.4064)
			(stroke
				(width 0.1524)
				(type default)
			)
			(layer "F.SilkS")
		)
		(fp_line
			(start -0.7874 -0.4064)
			(end 0.7874 -0.4064)
			(stroke
				(width 0.1524)
				(type default)
			)
			(layer "F.SilkS")
		)
		(fp_line
			(start 0.67945 0.3048)
			(end 0.120396 0.3048)
			(stroke
				(width 0.1)
				(type default)
			)
			(layer "F.Fab")
		)
		(fp_line
			(start 0.67945 -0.3048)
			(end 0.67945 0.3048)
			(stroke
				(width 0.1)
				(type default)
			)
			(layer "F.Fab")
		)
		(fp_line
			(start 0.12065 -0.2794)
			(end 0.12065 -0.3048)
			(stroke
				(width 0.1)
				(type default)
			)
			(layer "F.Fab")
		)
		(fp_line
			(start 0.12065 -0.3048)
			(end 0.67945 -0.3048)
			(stroke
				(width 0.1)
				(type default)
			)
			(layer "F.Fab")
		)
		(fp_line
			(start 0.120396 0.3048)
			(end 0.120396 0.2794)
			(stroke
				(width 0.1)
				(type default)
			)
			(layer "F.Fab")
		)
		(fp_line
			(start 0.120396 0.2794)
			(end -0.12065 0.2794)
			(stroke
				(width 0.1)
				(type default)
			)
			(layer "F.Fab")
		)
		(fp_line
			(start -0.12065 0.3048)
			(end -0.67945 0.3048)
			(stroke
				(width 0.1)
				(type default)
			)
			(layer "F.Fab")
		)
		(fp_line
			(start -0.12065 0.2794)
			(end -0.12065 0.3048)
			(stroke
				(width 0.1)
				(type default)
			)
			(layer "F.Fab")
		)
		(fp_line
			(start -0.12065 -0.2794)
			(end 0.12065 -0.2794)
			(stroke
				(width 0.1)
				(type default)
			)
			(layer "F.Fab")
		)
		(fp_line
			(start -0.12065 -0.305054)
			(end -0.12065 -0.2794)
			(stroke
				(width 0.1)
				(type default)
			)
			(layer "F.Fab")
		)
		(fp_line
			(start -0.67945 0.3048)
			(end -0.67945 -0.305054)
			(stroke
				(width 0.1)
				(type default)
			)
			(layer "F.Fab")
		)
		(fp_line
			(start -0.67945 -0.305054)
			(end -0.12065 -0.305054)
			(stroke
				(width 0.1)
				(type default)
			)
			(layer "F.Fab")
		)
		(pad "1" smd circle
			(at -0.40005 0 180)
			(size 0 0)
			(layers "F.Cu" "F.Mask" "F.Paste")
			(net "FPGA_PEX2_MODE_SEL1_D_N")
		)
		(pad "2" smd circle
			(at 0.40005 0 180)
			(size 0 0)
			(layers "F.Cu" "F.Mask" "F.Paste")
			(net "P3V3_AUX")
		)
	)
	(footprint ""
		(layer "F.Cu")
		(at 56.18861 -386.725668)
		(property "Reference" "C4042"
			(at 0 0 0)
			(layer "F.SilkS")
			(hide yes)
			(effects
				(font
					(size 1.27 1.27)
				)
			)
		)
		(property "Value" ""
			(at 0 0 0)
			(layer "F.Fab")
			(effects
				(font
					(size 1.27 1.27)
				)
			)
		)
		(duplicate_pad_numbers_are_jumpers no)
		(fp_line
			(start -0.7874 -0.4064)
			(end 0.7874 -0.4064)
			(stroke
				(width 0.1524)
				(type default)
			)
			(layer "F.SilkS")
		)
		(fp_line
			(start -0.7874 0.4064)
			(end -0.7874 -0.4064)
			(stroke
				(width 0.1524)
				(type default)
			)
			(layer "F.SilkS")
		)
		(fp_line
			(start 0.7874 -0.4064)
			(end 0.7874 0.4064)
			(stroke
				(width 0.1524)
				(type default)
			)
			(layer "F.SilkS")
		)
		(fp_line
			(start 0.7874 0.4064)
			(end -0.7874 0.4064)
			(stroke
				(width 0.1524)
				(type default)
			)
			(layer "F.SilkS")
		)
		(fp_line
			(start -0.67945 -0.305054)
			(end -0.12065 -0.305054)
			(stroke
				(width 0.1)
				(type default)
			)
			(layer "F.Fab")
		)
		(fp_line
			(start -0.67945 0.3048)
			(end -0.67945 -0.305054)
			(stroke
				(width 0.1)
				(type default)
			)
			(layer "F.Fab")
		)
		(fp_line
			(start -0.12065 -0.305054)
			(end -0.12065 -0.2794)
			(stroke
				(width 0.1)
				(type default)
			)
			(layer "F.Fab")
		)
		(fp_line
			(start -0.12065 -0.2794)
			(end 0.12065 -0.2794)
			(stroke
				(width 0.1)
				(type default)
			)
			(layer "F.Fab")
		)
		(fp_line
			(start -0.12065 0.2794)
			(end -0.12065 0.3048)
			(stroke
				(width 0.1)
				(type default)
			)
			(layer "F.Fab")
		)
		(fp_line
			(start -0.12065 0.3048)
			(end -0.67945 0.3048)
			(stroke
				(width 0.1)
				(type default)
			)
			(layer "F.Fab")
		)
		(fp_line
			(start 0.120396 0.2794)
			(end -0.12065 0.2794)
			(stroke
				(width 0.1)
				(type default)
			)
			(layer "F.Fab")
		)
		(fp_line
			(start 0.120396 0.3048)
			(end 0.120396 0.2794)
			(stroke
				(width 0.1)
				(type default)
			)
			(layer "F.Fab")
		)
		(fp_line
			(start 0.12065 -0.3048)
			(end 0.67945 -0.3048)
			(stroke
				(width 0.1)
				(type default)
			)
			(layer "F.Fab")
		)
		(fp_line
			(start 0.12065 -0.2794)
			(end 0.12065 -0.3048)
			(stroke
				(width 0.1)
				(type default)
			)
			(layer "F.Fab")
		)
		(fp_line
			(start 0.67945 -0.3048)
			(end 0.67945 0.3048)
			(stroke
				(width 0.1)
				(type default)
			)
			(layer "F.Fab")
		)
		(fp_line
			(start 0.67945 0.3048)
			(end 0.120396 0.3048)
			(stroke
				(width 0.1)
				(type default)
			)
			(layer "F.Fab")
		)
		(pad "1" smd circle
			(at -0.40005 0)
			(size 0 0)
			(layers "F.Cu" "F.Mask" "F.Paste")
			(net "GND")
		)
		(pad "2" smd circle
			(at 0.40005 0)
			(size 0 0)
			(layers "F.Cu" "F.Mask" "F.Paste")
			(net "GPU_BASE_ID0")
		)
	)
	(footprint ""
		(layer "F.Cu")
		(at 163.075112 -356.244906 90)
		(property "Reference" "C401"
			(at 0 0 90)
			(layer "F.SilkS")
			(hide yes)
			(effects
				(font
					(size 1.27 1.27)
				)
			)
		)
		(property "Value" ""
			(at 0 0 90)
			(layer "F.Fab")
			(effects
				(font
					(size 1.27 1.27)
				)
			)
		)
		(duplicate_pad_numbers_are_jumpers no)
		(fp_line
			(start 0.299974 -0.150114)
			(end 0.299974 0.150114)
			(stroke
				(width 0.1)
				(type default)
			)
			(layer "F.Fab")
		)
		(fp_line
			(start -0.299974 -0.150114)
			(end 0.299974 -0.150114)
			(stroke
				(width 0.1)
				(type default)
			)
			(layer "F.Fab")
		)
		(fp_line
			(start 0.299974 0.150114)
			(end -0.299974 0.150114)
			(stroke
				(width 0.1)
				(type default)
			)
			(layer "F.Fab")
		)
		(fp_line
			(start -0.299974 0.150114)
			(end -0.299974 -0.150114)
			(stroke
				(width 0.1)
				(type default)
			)
			(layer "F.Fab")
		)
		(pad "1" smd rect
			(at -0.2667 0 90)
			(size 0.3048 0.381)
			(layers "F.Cu" "F.Mask" "F.Paste")
			(net "P5E_PEX1_STN7_TX_DN<113>")
		)
		(pad "2" smd rect
			(at 0.2667 0 90)
			(size 0.3048 0.381)
			(layers "F.Cu" "F.Mask" "F.Paste")
			(net "P5E_PEX1_STN7_TX_C_DN<113>")
		)
	)
	(footprint ""
		(layer "F.Cu")
		(at 422.327832 -35.876738)
		(property "Reference" "R6119"
			(at 0 0 0)
			(layer "F.SilkS")
			(hide yes)
			(effects
				(font
					(size 1.27 1.27)
				)
			)
		)
		(property "Value" ""
			(at 0 0 0)
			(layer "F.Fab")
			(effects
				(font
					(size 1.27 1.27)
				)
			)
		)
		(duplicate_pad_numbers_are_jumpers no)
		(fp_line
			(start -0.7874 -0.4064)
			(end 0.7874 -0.4064)
			(stroke
				(width 0.1524)
				(type default)
			)
			(layer "F.SilkS")
		)
		(fp_line
			(start -0.7874 0.4064)
			(end -0.7874 -0.4064)
			(stroke
				(width 0.1524)
				(type default)
			)
			(layer "F.SilkS")
		)
		(fp_line
			(start 0.7874 -0.4064)
			(end 0.7874 0.4064)
			(stroke
				(width 0.1524)
				(type default)
			)
			(layer "F.SilkS")
		)
		(fp_line
			(start 0.7874 0.4064)
			(end -0.7874 0.4064)
			(stroke
				(width 0.1524)
				(type default)
			)
			(layer "F.SilkS")
		)
		(fp_line
			(start -0.67945 -0.305054)
			(end -0.12065 -0.305054)
			(stroke
				(width 0.1)
				(type default)
			)
			(layer "F.Fab")
		)
		(fp_line
			(start -0.67945 0.3048)
			(end -0.67945 -0.305054)
			(stroke
				(width 0.1)
				(type default)
			)
			(layer "F.Fab")
		)
		(fp_line
			(start -0.12065 -0.305054)
			(end -0.12065 -0.2794)
			(stroke
				(width 0.1)
				(type default)
			)
			(layer "F.Fab")
		)
		(fp_line
			(start -0.12065 -0.2794)
			(end 0.12065 -0.2794)
			(stroke
				(width 0.1)
				(type default)
			)
			(layer "F.Fab")
		)
		(fp_line
			(start -0.12065 0.2794)
			(end -0.12065 0.3048)
			(stroke
				(width 0.1)
				(type default)
			)
			(layer "F.Fab")
		)
		(fp_line
			(start -0.12065 0.3048)
			(end -0.67945 0.3048)
			(stroke
				(width 0.1)
				(type default)
			)
			(layer "F.Fab")
		)
		(fp_line
			(start 0.120396 0.2794)
			(end -0.12065 0.2794)
			(stroke
				(width 0.1)
				(type default)
			)
			(layer "F.Fab")
		)
		(fp_line
			(start 0.120396 0.3048)
			(end 0.120396 0.2794)
			(stroke
				(width 0.1)
				(type default)
			)
			(layer "F.Fab")
		)
		(fp_line
			(start 0.12065 -0.3048)
			(end 0.67945 -0.3048)
			(stroke
				(width 0.1)
				(type default)
			)
			(layer "F.Fab")
		)
		(fp_line
			(start 0.12065 -0.2794)
			(end 0.12065 -0.3048)
			(stroke
				(width 0.1)
				(type default)
			)
			(layer "F.Fab")
		)
		(fp_line
			(start 0.67945 -0.3048)
			(end 0.67945 0.3048)
			(stroke
				(width 0.1)
				(type default)
			)
			(layer "F.Fab")
		)
		(fp_line
			(start 0.67945 0.3048)
			(end 0.120396 0.3048)
			(stroke
				(width 0.1)
				(type default)
			)
			(layer "F.Fab")
		)
		(pad "1" smd circle
			(at -0.40005 0)
			(size 0 0)
			(layers "F.Cu" "F.Mask" "F.Paste")
			(net "PWRGD_P3V3_SSD15_D")
		)
		(pad "2" smd circle
			(at 0.40005 0)
			(size 0 0)
			(layers "F.Cu" "F.Mask" "F.Paste")
			(net "PWRGD_P3V3_SSD15_R")
		)
	)
	(footprint ""
		(layer "F.Cu")
		(at 424.78198 -37.025072)
		(property "Reference" "R5705"
			(at 0 0 0)
			(layer "F.SilkS")
			(hide yes)
			(effects
				(font
					(size 1.27 1.27)
				)
			)
		)
		(property "Value" ""
			(at 0 0 0)
			(layer "F.Fab")
			(effects
				(font
					(size 1.27 1.27)
				)
			)
		)
		(duplicate_pad_numbers_are_jumpers no)
		(fp_line
			(start -0.7874 -0.4064)
			(end 0.7874 -0.4064)
			(stroke
				(width 0.1524)
				(type default)
			)
			(layer "F.SilkS")
		)
		(fp_line
			(start -0.7874 0.4064)
			(end -0.7874 -0.4064)
			(stroke
				(width 0.1524)
				(type default)
			)
			(layer "F.SilkS")
		)
		(fp_line
			(start 0.7874 -0.4064)
			(end 0.7874 0.4064)
			(stroke
				(width 0.1524)
				(type default)
			)
			(layer "F.SilkS")
		)
		(fp_line
			(start 0.7874 0.4064)
			(end -0.7874 0.4064)
			(stroke
				(width 0.1524)
				(type default)
			)
			(layer "F.SilkS")
		)
		(fp_line
			(start -0.67945 -0.305054)
			(end -0.12065 -0.305054)
			(stroke
				(width 0.1)
				(type default)
			)
			(layer "F.Fab")
		)
		(fp_line
			(start -0.67945 0.3048)
			(end -0.67945 -0.305054)
			(stroke
				(width 0.1)
				(type default)
			)
			(layer "F.Fab")
		)
		(fp_line
			(start -0.12065 -0.305054)
			(end -0.12065 -0.2794)
			(stroke
				(width 0.1)
				(type default)
			)
			(layer "F.Fab")
		)
		(fp_line
			(start -0.12065 -0.2794)
			(end 0.12065 -0.2794)
			(stroke
				(width 0.1)
				(type default)
			)
			(layer "F.Fab")
		)
		(fp_line
			(start -0.12065 0.2794)
			(end -0.12065 0.3048)
			(stroke
				(width 0.1)
				(type default)
			)
			(layer "F.Fab")
		)
		(fp_line
			(start -0.12065 0.3048)
			(end -0.67945 0.3048)
			(stroke
				(width 0.1)
				(type default)
			)
			(layer "F.Fab")
		)
		(fp_line
			(start 0.120396 0.2794)
			(end -0.12065 0.2794)
			(stroke
				(width 0.1)
				(type default)
			)
			(layer "F.Fab")
		)
		(fp_line
			(start 0.120396 0.3048)
			(end 0.120396 0.2794)
			(stroke
				(width 0.1)
				(type default)
			)
			(layer "F.Fab")
		)
		(fp_line
			(start 0.12065 -0.3048)
			(end 0.67945 -0.3048)
			(stroke
				(width 0.1)
				(type default)
			)
			(layer "F.Fab")
		)
		(fp_line
			(start 0.12065 -0.2794)
			(end 0.12065 -0.3048)
			(stroke
				(width 0.1)
				(type default)
			)
			(layer "F.Fab")
		)
		(fp_line
			(start 0.67945 -0.3048)
			(end 0.67945 0.3048)
			(stroke
				(width 0.1)
				(type default)
			)
			(layer "F.Fab")
		)
		(fp_line
			(start 0.67945 0.3048)
			(end 0.120396 0.3048)
			(stroke
				(width 0.1)
				(type default)
			)
			(layer "F.Fab")
		)
		(pad "1" smd circle
			(at -0.40005 0)
			(size 0 0)
			(layers "F.Cu" "F.Mask" "F.Paste")
			(net "RST_SMB_SSD_R_N")
		)
		(pad "2" smd circle
			(at 0.40005 0)
			(size 0 0)
			(layers "F.Cu" "F.Mask" "F.Paste")
			(net "RST_SMB_SSD15_N")
		)
	)
	(footprint ""
		(layer "F.Cu")
		(at 270.807942 -159.4104 180)
		(property "Reference" "R206"
			(at 0 0 180)
			(layer "F.SilkS")
			(hide yes)
			(effects
				(font
					(size 1.27 1.27)
				)
			)
		)
		(property "Value" ""
			(at 0 0 180)
			(layer "F.Fab")
			(effects
				(font
					(size 1.27 1.27)
				)
			)
		)
		(duplicate_pad_numbers_are_jumpers no)
		(fp_line
			(start 0.7874 0.4064)
			(end -0.7874 0.4064)
			(stroke
				(width 0.1524)
				(type default)
			)
			(layer "F.SilkS")
		)
		(fp_line
			(start 0.7874 -0.4064)
			(end 0.7874 0.4064)
			(stroke
				(width 0.1524)
				(type default)
			)
			(layer "F.SilkS")
		)
		(fp_line
			(start -0.7874 0.4064)
			(end -0.7874 -0.4064)
			(stroke
				(width 0.1524)
				(type default)
			)
			(layer "F.SilkS")
		)
		(fp_line
			(start -0.7874 -0.4064)
			(end 0.7874 -0.4064)
			(stroke
				(width 0.1524)
				(type default)
			)
			(layer "F.SilkS")
		)
		(fp_line
			(start 0.67945 0.3048)
			(end 0.120396 0.3048)
			(stroke
				(width 0.1)
				(type default)
			)
			(layer "F.Fab")
		)
		(fp_line
			(start 0.67945 -0.3048)
			(end 0.67945 0.3048)
			(stroke
				(width 0.1)
				(type default)
			)
			(layer "F.Fab")
		)
		(fp_line
			(start 0.12065 -0.2794)
			(end 0.12065 -0.3048)
			(stroke
				(width 0.1)
				(type default)
			)
			(layer "F.Fab")
		)
		(fp_line
			(start 0.12065 -0.3048)
			(end 0.67945 -0.3048)
			(stroke
				(width 0.1)
				(type default)
			)
			(layer "F.Fab")
		)
		(fp_line
			(start 0.120396 0.3048)
			(end 0.120396 0.2794)
			(stroke
				(width 0.1)
				(type default)
			)
			(layer "F.Fab")
		)
		(fp_line
			(start 0.120396 0.2794)
			(end -0.12065 0.2794)
			(stroke
				(width 0.1)
				(type default)
			)
			(layer "F.Fab")
		)
		(fp_line
			(start -0.12065 0.3048)
			(end -0.67945 0.3048)
			(stroke
				(width 0.1)
				(type default)
			)
			(layer "F.Fab")
		)
		(fp_line
			(start -0.12065 0.2794)
			(end -0.12065 0.3048)
			(stroke
				(width 0.1)
				(type default)
			)
			(layer "F.Fab")
		)
		(fp_line
			(start -0.12065 -0.2794)
			(end 0.12065 -0.2794)
			(stroke
				(width 0.1)
				(type default)
			)
			(layer "F.Fab")
		)
		(fp_line
			(start -0.12065 -0.305054)
			(end -0.12065 -0.2794)
			(stroke
				(width 0.1)
				(type default)
			)
			(layer "F.Fab")
		)
		(fp_line
			(start -0.67945 0.3048)
			(end -0.67945 -0.305054)
			(stroke
				(width 0.1)
				(type default)
			)
			(layer "F.Fab")
		)
		(fp_line
			(start -0.67945 -0.305054)
			(end -0.12065 -0.305054)
			(stroke
				(width 0.1)
				(type default)
			)
			(layer "F.Fab")
		)
		(pad "1" smd circle
			(at -0.40005 0 180)
			(size 0 0)
			(layers "F.Cu" "F.Mask" "F.Paste")
			(net "NIC4_MAIN_PWR_EN_R")
		)
		(pad "2" smd circle
			(at 0.40005 0 180)
			(size 0 0)
			(layers "F.Cu" "F.Mask" "F.Paste")
			(net "NIC4_MAIN_PWR_EN")
		)
	)
	(footprint ""
		(layer "F.Cu")
		(at 460.611982 -113.563654)
		(property "Reference" "PC835"
			(at 0 0 0)
			(layer "F.SilkS")
			(hide yes)
			(effects
				(font
					(size 1.27 1.27)
				)
			)
		)
		(property "Value" ""
			(at 0 0 0)
			(layer "F.Fab")
			(effects
				(font
					(size 1.27 1.27)
				)
			)
		)
		(duplicate_pad_numbers_are_jumpers no)
		(fp_line
			(start -0.7874 -0.4064)
			(end 0.7874 -0.4064)
			(stroke
				(width 0.1524)
				(type default)
			)
			(layer "F.SilkS")
		)
		(fp_line
			(start -0.7874 0.4064)
			(end -0.7874 -0.4064)
			(stroke
				(width 0.1524)
				(type default)
			)
			(layer "F.SilkS")
		)
		(fp_line
			(start 0.7874 -0.4064)
			(end 0.7874 0.4064)
			(stroke
				(width 0.1524)
				(type default)
			)
			(layer "F.SilkS")
		)
		(fp_line
			(start 0.7874 0.4064)
			(end -0.7874 0.4064)
			(stroke
				(width 0.1524)
				(type default)
			)
			(layer "F.SilkS")
		)
		(fp_line
			(start -0.67945 -0.305054)
			(end -0.12065 -0.305054)
			(stroke
				(width 0.1)
				(type default)
			)
			(layer "F.Fab")
		)
		(fp_line
			(start -0.67945 0.3048)
			(end -0.67945 -0.305054)
			(stroke
				(width 0.1)
				(type default)
			)
			(layer "F.Fab")
		)
		(fp_line
			(start -0.12065 -0.305054)
			(end -0.12065 -0.2794)
			(stroke
				(width 0.1)
				(type default)
			)
			(layer "F.Fab")
		)
		(fp_line
			(start -0.12065 -0.2794)
			(end 0.12065 -0.2794)
			(stroke
				(width 0.1)
				(type default)
			)
			(layer "F.Fab")
		)
		(fp_line
			(start -0.12065 0.2794)
			(end -0.12065 0.3048)
			(stroke
				(width 0.1)
				(type default)
			)
			(layer "F.Fab")
		)
		(fp_line
			(start -0.12065 0.3048)
			(end -0.67945 0.3048)
			(stroke
				(width 0.1)
				(type default)
			)
			(layer "F.Fab")
		)
		(fp_line
			(start 0.120396 0.2794)
			(end -0.12065 0.2794)
			(stroke
				(width 0.1)
				(type default)
			)
			(layer "F.Fab")
		)
		(fp_line
			(start 0.120396 0.3048)
			(end 0.120396 0.2794)
			(stroke
				(width 0.1)
				(type default)
			)
			(layer "F.Fab")
		)
		(fp_line
			(start 0.12065 -0.3048)
			(end 0.67945 -0.3048)
			(stroke
				(width 0.1)
				(type default)
			)
			(layer "F.Fab")
		)
		(fp_line
			(start 0.12065 -0.2794)
			(end 0.12065 -0.3048)
			(stroke
				(width 0.1)
				(type default)
			)
			(layer "F.Fab")
		)
		(fp_line
			(start 0.67945 -0.3048)
			(end 0.67945 0.3048)
			(stroke
				(width 0.1)
				(type default)
			)
			(layer "F.Fab")
		)
		(fp_line
			(start 0.67945 0.3048)
			(end 0.120396 0.3048)
			(stroke
				(width 0.1)
				(type default)
			)
			(layer "F.Fab")
		)
		(pad "1" smd circle
			(at -0.40005 0)
			(size 0 0)
			(layers "F.Cu" "F.Mask" "F.Paste")
			(net "P12V_NIC7_CO_SS")
		)
		(pad "2" smd circle
			(at 0.40005 0)
			(size 0 0)
			(layers "F.Cu" "F.Mask" "F.Paste")
			(net "GND")
		)
	)
)
